(kicad_pcb
	(version 20260206)
	(generator "pcbnew")
	(generator_version "10.0")
	(general
		(thickness 1.6)
		(legacy_teardrops no)
	)
	(paper "A4")
	(title_block
		(title "03242023_DA0F0TMBIJ0_F0T_Motherboard_J_brd_V01_OCP.brd")
		(comment 1 "Grand Teton / footprints 1433-1439 of 6105")
	)
	(layers
		(0 "F.Cu" signal "TOP")
		(4 "In1.Cu" signal "GND")
		(6 "In2.Cu" signal "IN1")
		(8 "In3.Cu" signal "GND1")
		(10 "In4.Cu" signal "IN2")
		(12 "In5.Cu" signal "GND2")
		(14 "In6.Cu" signal "IN3")
		(16 "In7.Cu" signal "GND3")
		(18 "In8.Cu" signal "VCC")
		(20 "In9.Cu" signal "VCC1")
		(22 "In10.Cu" signal "GND4")
		(24 "In11.Cu" signal "IN4")
		(26 "In12.Cu" signal "GND5")
		(28 "In13.Cu" signal "IN5")
		(30 "In14.Cu" signal "GND6")
		(32 "In15.Cu" signal "IN6")
		(34 "In16.Cu" signal "GND7")
		(2 "B.Cu" signal "BOTTOM")
		(9 "F.Adhes" user "F.Adhesive")
		(11 "B.Adhes" user "B.Adhesive")
		(13 "F.Paste" user "Package Geometry/Pastemask Top")
		(15 "B.Paste" user "Package Geometry/Pastemask Bottom")
		(5 "F.SilkS" user "Ref Des/Silkscreen Top")
		(7 "B.SilkS" user "Ref Des/Silkscreen Bottom")
		(1 "F.Mask" user "Board Geometry/Soldermask Top")
		(3 "B.Mask" user "Board Geometry/Soldermask Bottom")
		(17 "Dwgs.User" user "User.Drawings")
		(19 "Cmts.User" user "User.Comments")
		(21 "Eco1.User" user "User.Eco1")
		(23 "Eco2.User" user "User.Eco2")
		(25 "Edge.Cuts" user "Board Geometry/Outline")
		(27 "Margin" user)
		(31 "F.CrtYd" user "Package Geometry/Place Bound Top")
		(29 "B.CrtYd" user "Package Geometry/Place Bound Bottom")
		(35 "F.Fab" user "Ref Des/Assembly Top")
		(33 "B.Fab" user "Ref Des/Assembly Bottom")
	)
	(footprint ""
		(layer "F.Cu")
		(at 62.35446 -147.84197)
		(property "Reference" "PL22"
			(at -3.52044 -4.364228 0)
			(unlocked yes)
			(layer "F.SilkS")
			(effects
				(font
					(size 0.7874 0.5842)
					(thickness 0.1524)
				)
				(justify left)
			)
		)
		(property "Value" ""
			(at 0 0 0)
			(layer "F.Fab")
			(effects
				(font
					(size 1.27 1.27)
				)
			)
		)
		(duplicate_pad_numbers_are_jumpers no)
		(fp_line
			(start -3.24993 -3.24993)
			(end 3.24993 -3.24993)
			(stroke
				(width 0.1524)
				(type default)
			)
			(layer "F.SilkS")
		)
		(fp_line
			(start -3.24993 -2.2352)
			(end -3.24993 -3.24993)
			(stroke
				(width 0.1524)
				(type default)
			)
			(layer "F.SilkS")
		)
		(fp_line
			(start -3.24993 3.24993)
			(end -3.24993 2.2352)
			(stroke
				(width 0.1524)
				(type default)
			)
			(layer "F.SilkS")
		)
		(fp_line
			(start 3.24993 -3.24993)
			(end 3.24993 -2.2352)
			(stroke
				(width 0.1524)
				(type default)
			)
			(layer "F.SilkS")
		)
		(fp_line
			(start 3.24993 2.2352)
			(end 3.24993 3.24993)
			(stroke
				(width 0.1524)
				(type default)
			)
			(layer "F.SilkS")
		)
		(fp_line
			(start 3.24993 3.24993)
			(end -3.24993 3.24993)
			(stroke
				(width 0.1524)
				(type default)
			)
			(layer "F.SilkS")
		)
		(fp_line
			(start -3.24993 -3.24993)
			(end 3.24993 -3.24993)
			(stroke
				(width 0.1)
				(type default)
			)
			(layer "F.Fab")
		)
		(fp_line
			(start -3.24993 3.24993)
			(end -3.24993 -3.24993)
			(stroke
				(width 0.1)
				(type default)
			)
			(layer "F.Fab")
		)
		(fp_line
			(start 3.24993 -3.24993)
			(end 3.24993 3.24993)
			(stroke
				(width 0.1)
				(type default)
			)
			(layer "F.Fab")
		)
		(fp_line
			(start 3.24993 3.24993)
			(end -3.24993 3.24993)
			(stroke
				(width 0.1)
				(type default)
			)
			(layer "F.Fab")
		)
		(pad "1" smd rect
			(at -2.29997 0)
			(size 2.0066 4.2164)
			(layers "F.Cu" "F.Mask" "F.Paste")
			(net "SW_PVCCINFAON_CPU1_SW2")
		)
		(pad "2" smd rect
			(at 2.29997 0)
			(size 2.0066 4.2164)
			(layers "F.Cu" "F.Mask" "F.Paste")
			(net "PVCCINFAON_CPU1")
		)
	)
	(footprint ""
		(layer "F.Cu")
		(at 205.397608 -408.887422)
		(property "Reference" "PR3917"
			(at 0 0 0)
			(layer "F.SilkS")
			(hide yes)
			(effects
				(font
					(size 1.27 1.27)
				)
			)
		)
		(property "Value" ""
			(at 0 0 0)
			(layer "F.Fab")
			(effects
				(font
					(size 1.27 1.27)
				)
			)
		)
		(duplicate_pad_numbers_are_jumpers no)
		(fp_line
			(start -0.7874 -0.4064)
			(end 0.7874 -0.4064)
			(stroke
				(width 0.1524)
				(type default)
			)
			(layer "F.SilkS")
		)
		(fp_line
			(start -0.7874 0.4064)
			(end -0.7874 -0.4064)
			(stroke
				(width 0.1524)
				(type default)
			)
			(layer "F.SilkS")
		)
		(fp_line
			(start 0.7874 -0.4064)
			(end 0.7874 0.4064)
			(stroke
				(width 0.1524)
				(type default)
			)
			(layer "F.SilkS")
		)
		(fp_line
			(start 0.7874 0.4064)
			(end -0.7874 0.4064)
			(stroke
				(width 0.1524)
				(type default)
			)
			(layer "F.SilkS")
		)
		(fp_line
			(start -0.67945 -0.305054)
			(end -0.12065 -0.305054)
			(stroke
				(width 0.1)
				(type default)
			)
			(layer "F.Fab")
		)
		(fp_line
			(start -0.67945 0.3048)
			(end -0.67945 -0.305054)
			(stroke
				(width 0.1)
				(type default)
			)
			(layer "F.Fab")
		)
		(fp_line
			(start -0.12065 -0.305054)
			(end -0.12065 -0.2794)
			(stroke
				(width 0.1)
				(type default)
			)
			(layer "F.Fab")
		)
		(fp_line
			(start -0.12065 -0.2794)
			(end 0.12065 -0.2794)
			(stroke
				(width 0.1)
				(type default)
			)
			(layer "F.Fab")
		)
		(fp_line
			(start -0.12065 0.2794)
			(end -0.12065 0.3048)
			(stroke
				(width 0.1)
				(type default)
			)
			(layer "F.Fab")
		)
		(fp_line
			(start -0.12065 0.3048)
			(end -0.67945 0.3048)
			(stroke
				(width 0.1)
				(type default)
			)
			(layer "F.Fab")
		)
		(fp_line
			(start 0.120396 0.2794)
			(end -0.12065 0.2794)
			(stroke
				(width 0.1)
				(type default)
			)
			(layer "F.Fab")
		)
		(fp_line
			(start 0.120396 0.3048)
			(end 0.120396 0.2794)
			(stroke
				(width 0.1)
				(type default)
			)
			(layer "F.Fab")
		)
		(fp_line
			(start 0.12065 -0.3048)
			(end 0.67945 -0.3048)
			(stroke
				(width 0.1)
				(type default)
			)
			(layer "F.Fab")
		)
		(fp_line
			(start 0.12065 -0.2794)
			(end 0.12065 -0.3048)
			(stroke
				(width 0.1)
				(type default)
			)
			(layer "F.Fab")
		)
		(fp_line
			(start 0.67945 -0.3048)
			(end 0.67945 0.3048)
			(stroke
				(width 0.1)
				(type default)
			)
			(layer "F.Fab")
		)
		(fp_line
			(start 0.67945 0.3048)
			(end 0.120396 0.3048)
			(stroke
				(width 0.1)
				(type default)
			)
			(layer "F.Fab")
		)
		(pad "1" smd circle
			(at -0.40005 0)
			(size 0 0)
			(layers "F.Cu" "F.Mask" "F.Paste")
			(net "HSC_SCREF")
		)
		(pad "2" smd circle
			(at 0.40005 0)
			(size 0 0)
			(layers "F.Cu" "F.Mask" "F.Paste")
			(net "HSC_SCREF_2")
		)
	)
	(footprint ""
		(layer "F.Cu")
		(at 183.69788 -126.964948 -90)
		(property "Reference" "R285"
			(at 0 0 270)
			(layer "F.SilkS")
			(hide yes)
			(effects
				(font
					(size 1.27 1.27)
				)
			)
		)
		(property "Value" ""
			(at 0 0 270)
			(layer "F.Fab")
			(effects
				(font
					(size 1.27 1.27)
				)
			)
		)
		(duplicate_pad_numbers_are_jumpers no)
		(fp_line
			(start -0.7874 0.4064)
			(end -0.7874 -0.4064)
			(stroke
				(width 0.1524)
				(type default)
			)
			(layer "F.SilkS")
		)
		(fp_line
			(start 0.7874 0.4064)
			(end -0.7874 0.4064)
			(stroke
				(width 0.1524)
				(type default)
			)
			(layer "F.SilkS")
		)
		(fp_line
			(start -0.7874 -0.4064)
			(end 0.7874 -0.4064)
			(stroke
				(width 0.1524)
				(type default)
			)
			(layer "F.SilkS")
		)
		(fp_line
			(start 0.7874 -0.4064)
			(end 0.7874 0.4064)
			(stroke
				(width 0.1524)
				(type default)
			)
			(layer "F.SilkS")
		)
		(fp_line
			(start -0.67945 0.3048)
			(end -0.67945 -0.305054)
			(stroke
				(width 0.1)
				(type default)
			)
			(layer "F.Fab")
		)
		(fp_line
			(start -0.12065 0.3048)
			(end -0.67945 0.3048)
			(stroke
				(width 0.1)
				(type default)
			)
			(layer "F.Fab")
		)
		(fp_line
			(start 0.120396 0.3048)
			(end 0.120396 0.2794)
			(stroke
				(width 0.1)
				(type default)
			)
			(layer "F.Fab")
		)
		(fp_line
			(start 0.67945 0.3048)
			(end 0.120396 0.3048)
			(stroke
				(width 0.1)
				(type default)
			)
			(layer "F.Fab")
		)
		(fp_line
			(start -0.12065 0.2794)
			(end -0.12065 0.3048)
			(stroke
				(width 0.1)
				(type default)
			)
			(layer "F.Fab")
		)
		(fp_line
			(start 0.120396 0.2794)
			(end -0.12065 0.2794)
			(stroke
				(width 0.1)
				(type default)
			)
			(layer "F.Fab")
		)
		(fp_line
			(start -0.12065 -0.2794)
			(end 0.12065 -0.2794)
			(stroke
				(width 0.1)
				(type default)
			)
			(layer "F.Fab")
		)
		(fp_line
			(start 0.12065 -0.2794)
			(end 0.12065 -0.3048)
			(stroke
				(width 0.1)
				(type default)
			)
			(layer "F.Fab")
		)
		(fp_line
			(start 0.12065 -0.3048)
			(end 0.67945 -0.3048)
			(stroke
				(width 0.1)
				(type default)
			)
			(layer "F.Fab")
		)
		(fp_line
			(start 0.67945 -0.3048)
			(end 0.67945 0.3048)
			(stroke
				(width 0.1)
				(type default)
			)
			(layer "F.Fab")
		)
		(fp_line
			(start -0.67945 -0.305054)
			(end -0.12065 -0.305054)
			(stroke
				(width 0.1)
				(type default)
			)
			(layer "F.Fab")
		)
		(fp_line
			(start -0.12065 -0.305054)
			(end -0.12065 -0.2794)
			(stroke
				(width 0.1)
				(type default)
			)
			(layer "F.Fab")
		)
		(pad "1" smd circle
			(at -0.40005 0 270)
			(size 0 0)
			(layers "F.Cu" "F.Mask" "F.Paste")
			(net "P3V3_AUX")
		)
		(pad "2" smd circle
			(at 0.40005 0 270)
			(size 0 0)
			(layers "F.Cu" "F.Mask" "F.Paste")
			(net "FM_CPU0_PKGID2")
		)
	)
	(footprint ""
		(layer "F.Cu")
		(at 458.298804 -76.588112 90)
		(property "Reference" "PC2260"
			(at 0 0 90)
			(layer "F.SilkS")
			(hide yes)
			(effects
				(font
					(size 1.27 1.27)
				)
			)
		)
		(property "Value" ""
			(at 0 0 90)
			(layer "F.Fab")
			(effects
				(font
					(size 1.27 1.27)
				)
			)
		)
		(duplicate_pad_numbers_are_jumpers no)
		(fp_line
			(start 1.524 -0.762)
			(end 1.524 0.762)
			(stroke
				(width 0.1524)
				(type default)
			)
			(layer "F.SilkS")
		)
		(fp_line
			(start -1.524 -0.762)
			(end 1.524 -0.762)
			(stroke
				(width 0.1524)
				(type default)
			)
			(layer "F.SilkS")
		)
		(fp_line
			(start 1.524 0.762)
			(end -1.524 0.762)
			(stroke
				(width 0.1524)
				(type default)
			)
			(layer "F.SilkS")
		)
		(fp_line
			(start -1.524 0.762)
			(end -1.524 -0.762)
			(stroke
				(width 0.1524)
				(type default)
			)
			(layer "F.SilkS")
		)
		(fp_line
			(start 1.1049 -0.724916)
			(end -1.1049 -0.724916)
			(stroke
				(width 0.1)
				(type default)
			)
			(layer "F.Fab")
		)
		(fp_line
			(start -1.1049 -0.724916)
			(end -1.1049 0.724916)
			(stroke
				(width 0.1)
				(type default)
			)
			(layer "F.Fab")
		)
		(fp_line
			(start 1.1049 0.724916)
			(end 1.1049 -0.724916)
			(stroke
				(width 0.1)
				(type default)
			)
			(layer "F.Fab")
		)
		(fp_line
			(start -1.1049 0.724916)
			(end 1.1049 0.724916)
			(stroke
				(width 0.1)
				(type default)
			)
			(layer "F.Fab")
		)
		(pad "1" smd rect
			(at -0.889 0 270)
			(size 1.016 1.27)
			(layers "F.Cu" "F.Mask" "F.Paste")
			(net "SW_P3V3_AUX_FLT")
		)
		(pad "2" smd rect
			(at 0.889 0 270)
			(size 1.016 1.27)
			(layers "F.Cu" "F.Mask" "F.Paste")
			(net "GND")
		)
	)
	(footprint ""
		(layer "F.Cu")
		(at 220.087444 -100.23348)
		(property "Reference" "C1561"
			(at 0 0 0)
			(layer "F.SilkS")
			(hide yes)
			(effects
				(font
					(size 1.27 1.27)
				)
			)
		)
		(property "Value" ""
			(at 0 0 0)
			(layer "F.Fab")
			(effects
				(font
					(size 1.27 1.27)
				)
			)
		)
		(duplicate_pad_numbers_are_jumpers no)
		(fp_line
			(start -0.7874 -0.4064)
			(end 0.7874 -0.4064)
			(stroke
				(width 0.1524)
				(type default)
			)
			(layer "F.SilkS")
		)
		(fp_line
			(start -0.7874 0.4064)
			(end -0.7874 -0.4064)
			(stroke
				(width 0.1524)
				(type default)
			)
			(layer "F.SilkS")
		)
		(fp_line
			(start 0.7874 -0.4064)
			(end 0.7874 0.4064)
			(stroke
				(width 0.1524)
				(type default)
			)
			(layer "F.SilkS")
		)
		(fp_line
			(start 0.7874 0.4064)
			(end -0.7874 0.4064)
			(stroke
				(width 0.1524)
				(type default)
			)
			(layer "F.SilkS")
		)
		(fp_line
			(start -0.67945 -0.305054)
			(end -0.12065 -0.305054)
			(stroke
				(width 0.1)
				(type default)
			)
			(layer "F.Fab")
		)
		(fp_line
			(start -0.67945 0.3048)
			(end -0.67945 -0.305054)
			(stroke
				(width 0.1)
				(type default)
			)
			(layer "F.Fab")
		)
		(fp_line
			(start -0.12065 -0.305054)
			(end -0.12065 -0.2794)
			(stroke
				(width 0.1)
				(type default)
			)
			(layer "F.Fab")
		)
		(fp_line
			(start -0.12065 -0.2794)
			(end 0.12065 -0.2794)
			(stroke
				(width 0.1)
				(type default)
			)
			(layer "F.Fab")
		)
		(fp_line
			(start -0.12065 0.2794)
			(end -0.12065 0.3048)
			(stroke
				(width 0.1)
				(type default)
			)
			(layer "F.Fab")
		)
		(fp_line
			(start -0.12065 0.3048)
			(end -0.67945 0.3048)
			(stroke
				(width 0.1)
				(type default)
			)
			(layer "F.Fab")
		)
		(fp_line
			(start 0.120396 0.2794)
			(end -0.12065 0.2794)
			(stroke
				(width 0.1)
				(type default)
			)
			(layer "F.Fab")
		)
		(fp_line
			(start 0.120396 0.3048)
			(end 0.120396 0.2794)
			(stroke
				(width 0.1)
				(type default)
			)
			(layer "F.Fab")
		)
		(fp_line
			(start 0.12065 -0.3048)
			(end 0.67945 -0.3048)
			(stroke
				(width 0.1)
				(type default)
			)
			(layer "F.Fab")
		)
		(fp_line
			(start 0.12065 -0.2794)
			(end 0.12065 -0.3048)
			(stroke
				(width 0.1)
				(type default)
			)
			(layer "F.Fab")
		)
		(fp_line
			(start 0.67945 -0.3048)
			(end 0.67945 0.3048)
			(stroke
				(width 0.1)
				(type default)
			)
			(layer "F.Fab")
		)
		(fp_line
			(start 0.67945 0.3048)
			(end 0.120396 0.3048)
			(stroke
				(width 0.1)
				(type default)
			)
			(layer "F.Fab")
		)
		(pad "1" smd circle
			(at -0.40005 0)
			(size 0 0)
			(layers "F.Cu" "F.Mask" "F.Paste")
			(net "U206_VDD")
		)
		(pad "2" smd circle
			(at 0.40005 0)
			(size 0 0)
			(layers "F.Cu" "F.Mask" "F.Paste")
			(net "GND")
		)
	)
	(footprint ""
		(layer "F.Cu")
		(at 354.261928 -258.726686 90)
		(property "Reference" "C966"
			(at 0 0 90)
			(layer "F.SilkS")
			(hide yes)
			(effects
				(font
					(size 1.27 1.27)
				)
			)
		)
		(property "Value" ""
			(at 0 0 90)
			(layer "F.Fab")
			(effects
				(font
					(size 1.27 1.27)
				)
			)
		)
		(duplicate_pad_numbers_are_jumpers no)
		(fp_line
			(start 0.7874 -0.4064)
			(end 0.7874 0.4064)
			(stroke
				(width 0.1524)
				(type default)
			)
			(layer "F.SilkS")
		)
		(fp_line
			(start -0.7874 -0.4064)
			(end 0.7874 -0.4064)
			(stroke
				(width 0.1524)
				(type default)
			)
			(layer "F.SilkS")
		)
		(fp_line
			(start 0.7874 0.4064)
			(end -0.7874 0.4064)
			(stroke
				(width 0.1524)
				(type default)
			)
			(layer "F.SilkS")
		)
		(fp_line
			(start -0.7874 0.4064)
			(end -0.7874 -0.4064)
			(stroke
				(width 0.1524)
				(type default)
			)
			(layer "F.SilkS")
		)
		(fp_line
			(start -0.12065 -0.305054)
			(end -0.12065 -0.2794)
			(stroke
				(width 0.1)
				(type default)
			)
			(layer "F.Fab")
		)
		(fp_line
			(start -0.67945 -0.305054)
			(end -0.12065 -0.305054)
			(stroke
				(width 0.1)
				(type default)
			)
			(layer "F.Fab")
		)
		(fp_line
			(start 0.67945 -0.3048)
			(end 0.67945 0.3048)
			(stroke
				(width 0.1)
				(type default)
			)
			(layer "F.Fab")
		)
		(fp_line
			(start 0.12065 -0.3048)
			(end 0.67945 -0.3048)
			(stroke
				(width 0.1)
				(type default)
			)
			(layer "F.Fab")
		)
		(fp_line
			(start 0.12065 -0.2794)
			(end 0.12065 -0.3048)
			(stroke
				(width 0.1)
				(type default)
			)
			(layer "F.Fab")
		)
		(fp_line
			(start -0.12065 -0.2794)
			(end 0.12065 -0.2794)
			(stroke
				(width 0.1)
				(type default)
			)
			(layer "F.Fab")
		)
		(fp_line
			(start 0.120396 0.2794)
			(end -0.12065 0.2794)
			(stroke
				(width 0.1)
				(type default)
			)
			(layer "F.Fab")
		)
		(fp_line
			(start -0.12065 0.2794)
			(end -0.12065 0.3048)
			(stroke
				(width 0.1)
				(type default)
			)
			(layer "F.Fab")
		)
		(fp_line
			(start 0.67945 0.3048)
			(end 0.120396 0.3048)
			(stroke
				(width 0.1)
				(type default)
			)
			(layer "F.Fab")
		)
		(fp_line
			(start 0.120396 0.3048)
			(end 0.120396 0.2794)
			(stroke
				(width 0.1)
				(type default)
			)
			(layer "F.Fab")
		)
		(fp_line
			(start -0.12065 0.3048)
			(end -0.67945 0.3048)
			(stroke
				(width 0.1)
				(type default)
			)
			(layer "F.Fab")
		)
		(fp_line
			(start -0.67945 0.3048)
			(end -0.67945 -0.305054)
			(stroke
				(width 0.1)
				(type default)
			)
			(layer "F.Fab")
		)
		(pad "1" smd circle
			(at -0.40005 0 90)
			(size 0 0)
			(layers "F.Cu" "F.Mask" "F.Paste")
			(net "PVCCIN_CPU0")
		)
		(pad "2" smd circle
			(at 0.40005 0 90)
			(size 0 0)
			(layers "F.Cu" "F.Mask" "F.Paste")
			(net "GND")
		)
	)
	(footprint ""
		(layer "F.Cu")
		(at 302.85436 -433.04587 90)
		(property "Reference" "R4131"
			(at 0 0 90)
			(layer "F.SilkS")
			(hide yes)
			(effects
				(font
					(size 1.27 1.27)
				)
			)
		)
		(property "Value" ""
			(at 0 0 90)
			(layer "F.Fab")
			(effects
				(font
					(size 1.27 1.27)
				)
			)
		)
		(duplicate_pad_numbers_are_jumpers no)
		(fp_line
			(start 0.7874 -0.4064)
			(end 0.7874 0.4064)
			(stroke
				(width 0.1524)
				(type default)
			)
			(layer "F.SilkS")
		)
		(fp_line
			(start -0.7874 -0.4064)
			(end 0.7874 -0.4064)
			(stroke
				(width 0.1524)
				(type default)
			)
			(layer "F.SilkS")
		)
		(fp_line
			(start 0.7874 0.4064)
			(end -0.7874 0.4064)
			(stroke
				(width 0.1524)
				(type default)
			)
			(layer "F.SilkS")
		)
		(fp_line
			(start -0.7874 0.4064)
			(end -0.7874 -0.4064)
			(stroke
				(width 0.1524)
				(type default)
			)
			(layer "F.SilkS")
		)
		(fp_line
			(start -0.12065 -0.305054)
			(end -0.12065 -0.2794)
			(stroke
				(width 0.1)
				(type default)
			)
			(layer "F.Fab")
		)
		(fp_line
			(start -0.67945 -0.305054)
			(end -0.12065 -0.305054)
			(stroke
				(width 0.1)
				(type default)
			)
			(layer "F.Fab")
		)
		(fp_line
			(start 0.67945 -0.3048)
			(end 0.67945 0.3048)
			(stroke
				(width 0.1)
				(type default)
			)
			(layer "F.Fab")
		)
		(fp_line
			(start 0.12065 -0.3048)
			(end 0.67945 -0.3048)
			(stroke
				(width 0.1)
				(type default)
			)
			(layer "F.Fab")
		)
		(fp_line
			(start 0.12065 -0.2794)
			(end 0.12065 -0.3048)
			(stroke
				(width 0.1)
				(type default)
			)
			(layer "F.Fab")
		)
		(fp_line
			(start -0.12065 -0.2794)
			(end 0.12065 -0.2794)
			(stroke
				(width 0.1)
				(type default)
			)
			(layer "F.Fab")
		)
		(fp_line
			(start 0.120396 0.2794)
			(end -0.12065 0.2794)
			(stroke
				(width 0.1)
				(type default)
			)
			(layer "F.Fab")
		)
		(fp_line
			(start -0.12065 0.2794)
			(end -0.12065 0.3048)
			(stroke
				(width 0.1)
				(type default)
			)
			(layer "F.Fab")
		)
		(fp_line
			(start 0.67945 0.3048)
			(end 0.120396 0.3048)
			(stroke
				(width 0.1)
				(type default)
			)
			(layer "F.Fab")
		)
		(fp_line
			(start 0.120396 0.3048)
			(end 0.120396 0.2794)
			(stroke
				(width 0.1)
				(type default)
			)
			(layer "F.Fab")
		)
		(fp_line
			(start -0.12065 0.3048)
			(end -0.67945 0.3048)
			(stroke
				(width 0.1)
				(type default)
			)
			(layer "F.Fab")
		)
		(fp_line
			(start -0.67945 0.3048)
			(end -0.67945 -0.305054)
			(stroke
				(width 0.1)
				(type default)
			)
			(layer "F.Fab")
		)
		(pad "1" smd circle
			(at -0.40005 0 90)
			(size 0 0)
			(layers "F.Cu" "F.Mask" "F.Paste")
			(net "P3V3_AUX")
		)
		(pad "2" smd circle
			(at 0.40005 0 90)
			(size 0 0)
			(layers "F.Cu" "F.Mask" "F.Paste")
			(net "GPU_3V3IO_RSVD3_FFU")
		)
	)
)
